FILE_TYPE = CONNECTIVITY;
{Allegro Design Entry HDL 16.6-p007 (v16-6-112F) 10/10/2012}
"PAGE_NUMBER" = 44;
0"NC";
1"M_A_DQS_DN<17:0>";
2"M_A_DQS_DP<17:0>";
3"M_A_DQ<63:0>";
4"M_A_MA<17:0>";
5"M_A_BA<1:0>";
6"M_A_BG<1:0>";
7"M_A_CLK_DP<3:0>";
8"M_A_CLK_DN<3:0>";
9"M_A_CS_N<7:0>";
10"M_A_CKE<3:0>";
11"M_A_ODT<3:0>";
12"M_A_ECC<7:0>";
13"GND\g";
14"PVTT_ABC\g";
15"PVPP_ABC\g";
16"GND\g";
17"GND\g";
18"P12V_NVDIMM_ABC\g";
19"GND\g";
20"PVPP_ABC\g";
21"PVDDQ_ABC\g";
22"M_A_VREF";
23"TP_CH_A_DIMM_A1_RFU_1";
24"TP_CH_A_DIMM_A1_RFU_2";
25"TP_CH_A_DIMM_A1_RFU_0";
26"SMB_DDR_ABC_VPP_SDA";
27"SMB_DDR_ABC_VPP_SCL";
28"M_A_ACT_N";
29"M_A_ALERT_N";
30"FM_ADR_COMPLETE_ABC_N";
31"FM_DIMM_EVENT_COD_N";
32"M_A_ECC<1>";
33"M_A_ECC<0>";
34"M_A_PAR";
35"M_ABC_RST_N";
36"M_A_CLK_DN<2>";
37"M_A_ECC<6>";
38"M_A_ECC<5>";
39"M_A_ECC<4>";
40"M_A_ECC<3>";
41"M_A_ECC<2>";
42"M_A_ECC<7>";
43"M_A_ODT<2>";
44"M_A_ODT<3>";
45"M_A_CKE<2>";
46"M_A_C<2>";
47"M_A_CLK_DP<2>";
48"M_A_CS_N<7>";
49"M_A_CS_N<6>";
50"M_A_CS_N<5>";
51"M_A_CKE<3>";
52"M_A_CS_N<4>";
53"M_A_CLK_DN<3>";
54"M_A_BA<1>";
55"M_A_MA<0>";
56"M_A_MA<1>";
57"M_A_CLK_DP<3>";
58"M_A_BG<0>";
59"M_A_BG<1>";
60"M_A_BA<0>";
61"M_A_MA<4>";
62"M_A_MA<5>";
63"M_A_MA<6>";
64"M_A_MA<7>";
65"M_A_MA<8>";
66"M_A_MA<9>";
67"M_A_MA<10>";
68"M_A_MA<11>";
69"M_A_MA<3>";
70"M_A_MA<2>";
71"M_A_MA<12>";
72"M_A_MA<13>";
73"M_A_MA<17>";
74"M_A_MA<14>";
75"M_A_MA<15>";
76"M_A_MA<16>";
77"M_A_DQ<63>";
78"M_A_DQ<29>";
79"M_A_DQ<28>";
80"M_A_DQ<62>";
81"M_A_DQ<61>";
82"M_A_DQ<60>";
83"M_A_DQ<59>";
84"M_A_DQ<56>";
85"M_A_DQ<55>";
86"M_A_DQ<46>";
87"M_A_DQ<45>";
88"M_A_DQ<44>";
89"M_A_DQ<43>";
90"M_A_DQ<42>";
91"M_A_DQ<41>";
92"M_A_DQ<40>";
93"M_A_DQ<39>";
94"M_A_DQ<34>";
95"M_A_DQ<33>";
96"M_A_DQ<32>";
97"M_A_DQ<31>";
98"M_A_DQ<30>";
99"M_A_DQ<25>";
100"M_A_DQ<22>";
101"M_A_DQ<21>";
102"M_A_DQ<16>";
103"M_A_DQ<13>";
104"M_A_DQ<12>";
105"M_A_DQ<10>";
106"M_A_DQ<8>";
107"M_A_DQ<7>";
108"M_A_DQ<1>";
109"M_A_DQ<0>";
110"M_A_DQ<35>";
111"M_A_DQ<36>";
112"M_A_DQ<38>";
113"M_A_DQ<27>";
114"M_A_DQ<26>";
115"M_A_DQ<15>";
116"M_A_DQ<17>";
117"M_A_DQ<57>";
118"M_A_DQ<58>";
119"M_A_DQ<54>";
120"M_A_DQ<53>";
121"M_A_DQ<52>";
122"M_A_DQ<51>";
123"M_A_DQ<50>";
124"M_A_DQ<49>";
125"M_A_DQ<48>";
126"M_A_DQ<47>";
127"M_A_DQ<2>";
128"M_A_DQ<3>";
129"M_A_DQ<4>";
130"M_A_DQ<5>";
131"M_A_DQ<37>";
132"M_A_DQ<24>";
133"M_A_DQ<23>";
134"M_A_DQ<14>";
135"M_A_DQ<18>";
136"M_A_DQ<11>";
137"M_A_DQ<20>";
138"M_A_DQ<19>";
139"M_A_DQ<9>";
140"M_A_DQ<6>";
141"M_A_DQS_DP<1>";
142"M_A_DQS_DP<0>";
143"M_A_DQS_DP<4>";
144"M_A_DQS_DP<3>";
145"M_A_DQS_DP<2>";
146"M_A_DQS_DN<4>";
147"M_A_DQS_DN<3>";
148"M_A_DQS_DN<2>";
149"M_A_DQS_DN<1>";
150"M_A_DQS_DN<0>";
151"M_A_DQS_DP<6>";
152"M_A_DQS_DP<5>";
153"M_A_DQS_DP<9>";
154"M_A_DQS_DP<8>";
155"M_A_DQS_DP<7>";
156"M_A_DQS_DN<9>";
157"M_A_DQS_DN<8>";
158"M_A_DQS_DN<7>";
159"M_A_DQS_DN<6>";
160"M_A_DQS_DN<5>";
161"M_A_DQS_DP<12>";
162"M_A_DQS_DP<11>";
163"M_A_DQS_DP<10>";
164"M_A_DQS_DP<14>";
165"M_A_DQS_DP<13>";
166"M_A_DQS_DN<15>";
167"M_A_DQS_DN<14>";
168"M_A_DQS_DN<13>";
169"M_A_DQS_DN<12>";
170"M_A_DQS_DN<11>";
171"M_A_DQS_DN<10>";
172"M_A_DQS_DP<17>";
173"M_A_DQS_DP<16>";
174"M_A_DQS_DP<15>";
175"M_A_DQS_DN<17>";
176"M_A_DQS_DN<16>";
%"GND"
"1","(-2650,750)","0","mstr_symbols","I1";
;
HDL_POWER"GND"
ROOM"DDR4_CH_A"
BODY_TYPE"PLUMBING"
SIZE"1B"
CDS_LIB"mstr_symbols"
BOM_COST"MEM"
VOLTAGE"0";
"A\NAC"13;
%"TAP"
"6","(100,3150)","2","mstr_standard","I100";
;
HDL_TAP"TRUE"
BODY_TYPE"PLUMBING"
CDS_LIB"mstr_standard";
"B \NAC \NWC"3;
"S \NAC"
BN"39"93;
%"TAP"
"6","(100,3200)","2","mstr_standard","I101";
;
HDL_TAP"TRUE"
BODY_TYPE"PLUMBING"
CDS_LIB"mstr_standard";
"B \NAC \NWC"3;
"S \NAC"
BN"40"92;
%"TAP"
"6","(100,3250)","2","mstr_standard","I102";
;
HDL_TAP"TRUE"
BODY_TYPE"PLUMBING"
CDS_LIB"mstr_standard";
"B \NAC \NWC"3;
"S \NAC"
BN"41"91;
%"TAP"
"6","(100,3300)","2","mstr_standard","I103";
;
HDL_TAP"TRUE"
BODY_TYPE"PLUMBING"
CDS_LIB"mstr_standard";
"B \NAC \NWC"3;
"S \NAC"
BN"42"90;
%"TAP"
"6","(100,3400)","2","mstr_standard","I104";
;
HDL_TAP"TRUE"
BODY_TYPE"PLUMBING"
CDS_LIB"mstr_standard";
"B \NAC \NWC"3;
"S \NAC"
BN"44"88;
%"TAP"
"6","(100,3350)","2","mstr_standard","I105";
;
HDL_TAP"TRUE"
BODY_TYPE"PLUMBING"
CDS_LIB"mstr_standard";
"B \NAC \NWC"3;
"S \NAC"
BN"43"89;
%"TAP"
"6","(100,3450)","2","mstr_standard","I106";
;
HDL_TAP"TRUE"
BODY_TYPE"PLUMBING"
CDS_LIB"mstr_standard";
"B \NAC \NWC"3;
"S \NAC"
BN"45"87;
%"TAP"
"6","(100,3500)","2","mstr_standard","I107";
;
HDL_TAP"TRUE"
BODY_TYPE"PLUMBING"
CDS_LIB"mstr_standard";
"B \NAC \NWC"3;
"S \NAC"
BN"46"86;
%"TAP"
"6","(100,3650)","2","mstr_standard","I108";
;
HDL_TAP"TRUE"
BODY_TYPE"PLUMBING"
CDS_LIB"mstr_standard";
"B \NAC \NWC"3;
"S \NAC"
BN"49"124;
%"TAP"
"6","(100,3600)","2","mstr_standard","I109";
;
HDL_TAP"TRUE"
BODY_TYPE"PLUMBING"
CDS_LIB"mstr_standard";
"B \NAC \NWC"3;
"S \NAC"
BN"48"125;
%"TAP"
"6","(100,3550)","2","mstr_standard","I110";
;
HDL_TAP"TRUE"
BODY_TYPE"PLUMBING"
CDS_LIB"mstr_standard";
"B \NAC \NWC"3;
"S \NAC"
BN"47"126;
%"TAP"
"6","(100,3700)","2","mstr_standard","I111";
;
HDL_TAP"TRUE"
BODY_TYPE"PLUMBING"
CDS_LIB"mstr_standard";
"B \NAC \NWC"3;
"S \NAC"
BN"50"123;
%"TAP"
"6","(100,3750)","2","mstr_standard","I112";
;
HDL_TAP"TRUE"
BODY_TYPE"PLUMBING"
CDS_LIB"mstr_standard";
"B \NAC \NWC"3;
"S \NAC"
BN"51"122;
%"TAP"
"6","(100,3850)","2","mstr_standard","I113";
;
HDL_TAP"TRUE"
BODY_TYPE"PLUMBING"
CDS_LIB"mstr_standard";
"B \NAC \NWC"3;
"S \NAC"
BN"53"120;
%"TAP"
"6","(100,3800)","2","mstr_standard","I114";
;
HDL_TAP"TRUE"
BODY_TYPE"PLUMBING"
CDS_LIB"mstr_standard";
"B \NAC \NWC"3;
"S \NAC"
BN"52"121;
%"TAP"
"6","(100,3900)","2","mstr_standard","I115";
;
HDL_TAP"TRUE"
BODY_TYPE"PLUMBING"
CDS_LIB"mstr_standard";
"B \NAC \NWC"3;
"S \NAC"
BN"54"119;
%"TAP"
"6","(100,3950)","2","mstr_standard","I116";
;
HDL_TAP"TRUE"
BODY_TYPE"PLUMBING"
CDS_LIB"mstr_standard";
"B \NAC \NWC"3;
"S \NAC"
BN"55"85;
%"TAP"
"6","(100,4000)","2","mstr_standard","I117";
;
HDL_TAP"TRUE"
BODY_TYPE"PLUMBING"
CDS_LIB"mstr_standard";
"B \NAC \NWC"3;
"S \NAC"
BN"56"84;
%"PVTT_ABC"
"1","(800,2350)","0","mstr_symbols","I118";
;
HDL_POWER"PVTT_ABC"
ROOM"DDR4_CH_A"
BODY_TYPE"PLUMBING"
CDS_LIB"mstr_symbols"
BOM_COST"MEM"
VOLTAGE"0.6V";
"G\NAC"14;
%"PVPP_ABC"
"1","(950,2650)","0","mstr_symbols","I119";
;
HDL_POWER"PVPP_ABC"
ROOM"DDR4_CH_A"
BODY_TYPE"PLUMBING"
CDS_LIB"mstr_symbols"
BOM_COST"MEM"
VOLTAGE"2.5V";
"G\NAC"15;
%"TAP"
"6","(-1450,1950)","0","mstr_standard","I12";
;
HDL_TAP"TRUE"
BODY_TYPE"PLUMBING"
CDS_LIB"mstr_standard";
"B \NAC \NWC"12;
"S \NAC"
BN"0"33;
%"SCONN288_H44441003"
"2","(1650,4000)","0","mstr_sconn","I120";
;
CDS_SEC"2"
ROOM"DDR4_CH_A"
CDS_LOCATION"J6T1"
SEC"2"
SEC_TYPE"PIP"
CDS_LIB"mstr_sconn"
BOM_COST"MEM"
PACK_TYPE"PIP"
MATERIAL"SCONN"
PART_NUMBER"H44441-003"
LOCATION"J6T1";
"DQS0N"
$PN"152"150;
"DQS0P"
$PN"153"142;
"DQS10N"
$PN"19"171;
"DQS10P"
$PN"18"163;
"DQS11N"
$PN"30"170;
"DQS11P"
$PN"29"162;
"DQS12N"
$PN"41"169;
"DQS12P"
$PN"40"161;
"DQS13N"
$PN"100"168;
"DQS13P"
$PN"99"165;
"DQS14N"
$PN"111"167;
"DQS14P"
$PN"110"164;
"DQS15N"
$PN"122"166;
"DQS15P"
$PN"121"174;
"DQS16N"
$PN"133"176;
"DQS16P"
$PN"132"173;
"DQS17N"
$PN"52"175;
"DQS17P"
$PN"51"172;
"DQS1N"
$PN"163"149;
"DQS1P"
$PN"164"141;
"DQS2N"
$PN"174"148;
"DQS2P"
$PN"175"145;
"DQS3N"
$PN"185"147;
"DQS3P"
$PN"186"144;
"DQS4N"
$PN"244"146;
"DQS4P"
$PN"245"143;
"DQS5N"
$PN"255"160;
"DQS5P"
$PN"256"152;
"DQS6N"
$PN"266"159;
"DQS6P"
$PN"267"151;
"DQS7N"
$PN"277"158;
"DQS7P"
$PN"278"155;
"DQS8N"
$PN"196"157;
"DQS8P"
$PN"197"154;
"DQS9N"
$PN"8"156;
"DQS9P"
$PN"7"153;
%"TAP"
"6","(-1450,4150)","0","mstr_standard","I122";
;
HDL_TAP"TRUE"
BODY_TYPE"PLUMBING"
CDS_LIB"mstr_standard";
"B \NAC \NWC"4;
"S \NAC"
BN"13"72;
%"TAP"
"6","(-1450,4050)","0","mstr_standard","I123";
;
HDL_TAP"TRUE"
BODY_TYPE"PLUMBING"
CDS_LIB"mstr_standard";
"B \NAC \NWC"4;
"S \NAC"
BN"11"68;
%"TAP"
"6","(-1450,4100)","0","mstr_standard","I124";
;
HDL_TAP"TRUE"
BODY_TYPE"PLUMBING"
CDS_LIB"mstr_standard";
"B \NAC \NWC"4;
"S \NAC"
BN"12"71;
%"TAP"
"6","(-1450,4200)","0","mstr_standard","I125";
;
HDL_TAP"TRUE"
BODY_TYPE"PLUMBING"
CDS_LIB"mstr_standard";
"B \NAC \NWC"4;
"S \NAC"
BN"14"74;
%"TAP"
"6","(-1450,4250)","0","mstr_standard","I126";
;
HDL_TAP"TRUE"
BODY_TYPE"PLUMBING"
CDS_LIB"mstr_standard";
"B \NAC \NWC"4;
"S \NAC"
BN"15"75;
%"TAP"
"6","(-1450,4300)","0","mstr_standard","I127";
;
HDL_TAP"TRUE"
BODY_TYPE"PLUMBING"
CDS_LIB"mstr_standard";
"B \NAC \NWC"4;
"S \NAC"
BN"16"76;
%"TAP"
"6","(-1450,4350)","0","mstr_standard","I128";
;
HDL_TAP"TRUE"
BODY_TYPE"PLUMBING"
CDS_LIB"mstr_standard";
"B \NAC \NWC"4;
"S \NAC"
BN"17"73;
%"TAP"
"6","(100,4050)","2","mstr_standard","I129";
;
HDL_TAP"TRUE"
BODY_TYPE"PLUMBING"
CDS_LIB"mstr_standard";
"B \NAC \NWC"3;
"S \NAC"
BN"57"117;
%"SCONN288_H44441003"
"1","(-700,2700)","0","mstr_sconn","I13";
;
CDS_SEC"1"
ROOM"DDR4_CH_A"
CDS_LOCATION"J6T1"
SEC"1"
SEC_TYPE"PIP"
CDS_LIB"mstr_sconn"
BOM_COST"MEM"
PACK_TYPE"PIP"
MATERIAL"SCONN"
PART_NUMBER"H44441-003"
LOCATION"J6T1";
"DQ<63>"
$PN"280"77;
"BA<1>"
$PN"224"54;
"CK1N"
$PN"219"53;
"CK0P"
$PN"74"47;
"S3_N_C<1>"
$PN"237"48;
"S2_N_C<0>"
$PN"93"49;
"S1_N"
$PN"89"50;
"DQ<29>"
$PN"181"78;
"DQ<28>"
$PN"36"79;
"C<2>"
$PN"235"46;
"A0"
$PN"79"55;
"A1"
$PN"72"56;
"A12"
$PN"65"71;
"A13"
$PN"232"72;
"A17"
$PN"234"73;
"A3"
$PN"71"69;
"A4"
$PN"214"61;
"A5"
$PN"213"62;
"A6"
$PN"69"63;
"A7"
$PN"211"64;
"A8"
$PN"68"65;
"A9"
$PN"66"66;
"CB<6>"
$PN"54"37;
"CB<5>"
$PN"192"38;
"CB<4>"
$PN"47"39;
"CB<3>"
$PN"201"40;
"CB<2>"
$PN"56"41;
"CB<1>"
$PN"194"32;
"CB<0>"
$PN"49"33;
"CK0N"
$PN"75"36;
"CKE<1>"
$PN"203"51;
"DQ<62>"
$PN"135"80;
"DQ<61>"
$PN"273"81;
"DQ<60>"
$PN"128"82;
"DQ<59>"
$PN"282"83;
"DQ<56>"
$PN"130"84;
"DQ<55>"
$PN"269"85;
"DQ<46>"
$PN"113"86;
"DQ<45>"
$PN"251"87;
"DQ<44>"
$PN"106"88;
"DQ<43>"
$PN"260"89;
"DQ<42>"
$PN"115"90;
"DQ<41>"
$PN"253"91;
"DQ<40>"
$PN"108"92;
"DQ<39>"
$PN"247"93;
"DQ<37>"
$PN"240"131;
"DQ<34>"
$PN"104"94;
"DQ<33>"
$PN"242"95;
"DQ<32>"
$PN"97"96;
"DQ<31>"
$PN"188"97;
"DQ<30>"
$PN"43"98;
"DQ<25>"
$PN"183"99;
"DQ<24>"
$PN"38"132;
"DQ<23>"
$PN"177"133;
"DQ<22>"
$PN"32"100;
"DQ<21>"
$PN"170"101;
"DQ<20>"
$PN"25"137;
"DQ<19>"
$PN"179"138;
"DQ<18>"
$PN"34"135;
"DQ<16>"
$PN"27"102;
"DQ<14>"
$PN"21"134;
"DQ<13>"
$PN"159"103;
"DQ<12>"
$PN"14"104;
"DQ<11>"
$PN"168"136;
"DQ<10>"
$PN"23"105;
"DQ<9>"
$PN"161"139;
"DQ<8>"
$PN"16"106;
"DQ<7>"
$PN"155"107;
"DQ<6>"
$PN"10"140;
"EVENT_N"
$PN"78"31;
"PAR"
$PN"222"34;
"RESET_N"
$PN"58"35;
"RFU<2>"
$PN"144"24;
"SCL"
$PN"141"27;
"SDA"
$PN"285"26;
"VREFCA"
$PN"146"22;
"CK1P"
$PN"218"57;
"BG<0>"
$PN"63"58;
"BG<1>"
$PN"207"59;
"BA<0>"
$PN"81"60;
"SA<0>"
$PN"139"20;
"VDDSPD"
$PN"284"20;
"SA<2>"
$PN"238"19;
"SA<1>"
$PN"140"19;
"DQ<1>"
$PN"150"108;
"DQ<0>"
$PN"5"109;
"ACT_N"
$PN"62"28;
"ALERT_N"
$PN"208"29;
"A2"
$PN"216"70;
"DQ<35>"
$PN"249"110;
"DQ<36>"
$PN"95"111;
"DQ<38>"
$PN"102"112;
"A10"
$PN"225"67;
"A11"
$PN"210"68;
"A14_WE_N"
$PN"228"74;
"A15_CAS_N"
$PN"86"75;
"A16_RAS_N"
$PN"82"76;
"CB<7>"
$PN"199"42;
"ODT<0>"
$PN"87"43;
"ODT<1>"
$PN"91"44;
"CKE<0>"
$PN"60"45;
"S0_N"
$PN"84"52;
"DQ<27>"
$PN"190"113;
"DQ<26>"
$PN"45"114;
"DQ<15>"
$PN"166"115;
"DQ<17>"
$PN"172"116;
"RFU<0>"
$PN"205"25;
"RFU<1>"
$PN"227"23;
"SAVE_N_NC"
$PN"230"30;
"DQ<57>"
$PN"275"117;
"DQ<58>"
$PN"137"118;
"DQ<54>"
$PN"124"119;
"DQ<53>"
$PN"262"120;
"DQ<52>"
$PN"117"121;
"DQ<51>"
$PN"271"122;
"DQ<50>"
$PN"126"123;
"DQ<49>"
$PN"264"124;
"DQ<48>"
$PN"119"125;
"DQ<47>"
$PN"258"126;
"DQ<2>"
$PN"12"127;
"DQ<3>"
$PN"157"128;
"DQ<4>"
$PN"3"129;
"DQ<5>"
$PN"148"130;
%"TAP"
"6","(100,4100)","2","mstr_standard","I130";
;
HDL_TAP"TRUE"
BODY_TYPE"PLUMBING"
CDS_LIB"mstr_standard";
"B \NAC \NWC"3;
"S \NAC"
BN"58"118;
%"TAP"
"6","(100,4150)","2","mstr_standard","I131";
;
HDL_TAP"TRUE"
BODY_TYPE"PLUMBING"
CDS_LIB"mstr_standard";
"B \NAC \NWC"3;
"S \NAC"
BN"59"83;
%"TAP"
"6","(100,4200)","2","mstr_standard","I132";
;
HDL_TAP"TRUE"
BODY_TYPE"PLUMBING"
CDS_LIB"mstr_standard";
"B \NAC \NWC"3;
"S \NAC"
BN"60"82;
%"TAP"
"6","(100,4300)","2","mstr_standard","I133";
;
HDL_TAP"TRUE"
BODY_TYPE"PLUMBING"
CDS_LIB"mstr_standard";
"B \NAC \NWC"3;
"S \NAC"
BN"62"80;
%"TAP"
"6","(100,4250)","2","mstr_standard","I134";
;
HDL_TAP"TRUE"
BODY_TYPE"PLUMBING"
CDS_LIB"mstr_standard";
"B \NAC \NWC"3;
"S \NAC"
BN"61"81;
%"TAP"
"6","(100,4350)","2","mstr_standard","I135";
;
HDL_TAP"TRUE"
BODY_TYPE"PLUMBING"
CDS_LIB"mstr_standard";
"B \NAC \NWC"3;
"S \NAC"
BN"63"77;
%"GND"
"1","(2750,1100)","2","mstr_symbols","I138";
;
HDL_POWER"GND"
ROOM"DDR4_CH_A"
BODY_TYPE"PLUMBING"
SIZE"1B"
CDS_LIB"mstr_symbols"
BOM_COST"MEM"
VOLTAGE"0";
"A\NAC"16;
%"SCONN288_H44441003"
"3","(3450,2400)","0","mstr_sconn","I139";
;
CDS_SEC"3"
ROOM"DDR4_CH_A"
CDS_LOCATION"J6T1"
SEC"3"
SEC_TYPE"PIP"
CDS_LIB"mstr_sconn"
BOM_COST"MEM"
PACK_TYPE"PIP"
MATERIAL"SCONN"
PART_NUMBER"H44441-003"
LOCATION"J6T1";
"VSS<46>"
$PN"147"17;
"VSS<45>"
$PN"149"17;
"VSS<87>"
$PN"15"16;
"VSS<86>"
$PN"17"16;
"VSS<85>"
$PN"20"16;
"VSS<84>"
$PN"22"16;
"VSS<83>"
$PN"24"16;
"VSS<82>"
$PN"26"16;
"VSS<81>"
$PN"28"16;
"VSS<80>"
$PN"31"16;
"VSS<79>"
$PN"33"16;
"VSS<78>"
$PN"35"16;
"VSS<77>"
$PN"37"16;
"VSS<76>"
$PN"39"16;
"VSS<75>"
$PN"42"16;
"VSS<74>"
$PN"44"16;
"VSS<73>"
$PN"46"16;
"VSS<72>"
$PN"48"16;
"VSS<71>"
$PN"50"16;
"VSS<70>"
$PN"53"16;
"VSS<69>"
$PN"55"16;
"VSS<68>"
$PN"57"16;
"VSS<67>"
$PN"94"16;
"VSS<66>"
$PN"96"16;
"VSS<65>"
$PN"98"16;
"VSS<64>"
$PN"101"16;
"VSS<63>"
$PN"103"16;
"VSS<62>"
$PN"105"16;
"VSS<61>"
$PN"107"16;
"VSS<60>"
$PN"109"16;
"VSS<59>"
$PN"112"16;
"VSS<58>"
$PN"114"16;
"VSS<57>"
$PN"116"16;
"VSS<56>"
$PN"118"16;
"VSS<55>"
$PN"120"16;
"VSS<54>"
$PN"123"16;
"VSS<53>"
$PN"125"16;
"VSS<52>"
$PN"127"16;
"VSS<51>"
$PN"129"16;
"VSS<50>"
$PN"131"16;
"VSS<49>"
$PN"134"16;
"VSS<48>"
$PN"136"16;
"VSS<47>"
$PN"138"16;
"VSS<44>"
$PN"151"17;
"VSS<43>"
$PN"154"17;
"VSS<42>"
$PN"156"17;
"VSS<41>"
$PN"158"17;
"VSS<40>"
$PN"160"17;
"VSS<39>"
$PN"162"17;
"VSS<38>"
$PN"165"17;
"VSS<37>"
$PN"167"17;
"VSS<36>"
$PN"169"17;
"VSS<35>"
$PN"171"17;
"VSS<34>"
$PN"173"17;
"VSS<33>"
$PN"176"17;
"VSS<32>"
$PN"178"17;
"VSS<31>"
$PN"180"17;
"VSS<30>"
$PN"182"17;
"VSS<29>"
$PN"184"17;
"VSS<28>"
$PN"187"17;
"VSS<27>"
$PN"189"17;
"VSS<26>"
$PN"191"17;
"VSS<25>"
$PN"193"17;
"VSS<24>"
$PN"195"17;
"VSS<23>"
$PN"198"17;
"VSS<22>"
$PN"200"17;
"VSS<21>"
$PN"202"17;
"VSS<20>"
$PN"239"17;
"VSS<19>"
$PN"241"17;
"VSS<18>"
$PN"243"17;
"VSS<17>"
$PN"246"17;
"VSS<16>"
$PN"248"17;
"VSS<15>"
$PN"250"17;
"VSS<14>"
$PN"252"17;
"VSS<13>"
$PN"254"17;
"VSS<12>"
$PN"257"17;
"VSS<11>"
$PN"259"17;
"VSS<10>"
$PN"261"17;
"VSS<9>"
$PN"263"17;
"VSS<8>"
$PN"265"17;
"VSS<7>"
$PN"268"17;
"VSS<6>"
$PN"270"17;
"VSS<5>"
$PN"272"17;
"VSS<4>"
$PN"274"17;
"VSS<3>"
$PN"276"17;
"VSS<2>"
$PN"279"17;
"VSS<1>"
$PN"281"17;
"VSS<0>"
$PN"283"17;
"VSS<88>"
$PN"13"16;
"VSS<89>"
$PN"11"16;
"VSS<90>"
$PN"9"16;
"VSS<91>"
$PN"6"16;
"VSS<92>"
$PN"4"16;
"VSS<93>"
$PN"2"16;
%"TAP"
"6","(2350,3150)","2","mstr_standard","I142";
;
HDL_TAP"TRUE"
BODY_TYPE"PLUMBING"
CDS_LIB"mstr_standard";
"B \NAC \NWC"2;
"S \NAC"
BN"0"142;
%"TAP"
"6","(2350,3250)","2","mstr_standard","I143";
;
HDL_TAP"TRUE"
BODY_TYPE"PLUMBING"
CDS_LIB"mstr_standard";
"B \NAC \NWC"2;
"S \NAC"
BN"1"141;
%"TAP"
"6","(2350,3450)","2","mstr_standard","I144";
;
HDL_TAP"TRUE"
BODY_TYPE"PLUMBING"
CDS_LIB"mstr_standard";
"B \NAC \NWC"2;
"S \NAC"
BN"3"144;
%"TAP"
"6","(2350,3350)","2","mstr_standard","I145";
;
HDL_TAP"TRUE"
BODY_TYPE"PLUMBING"
CDS_LIB"mstr_standard";
"B \NAC \NWC"2;
"S \NAC"
BN"2"145;
%"TAP"
"6","(2550,3100)","2","mstr_standard","I146";
;
HDL_TAP"TRUE"
BODY_TYPE"PLUMBING"
CDS_LIB"mstr_standard";
"B \NAC \NWC"1;
"S \NAC"
BN"0"150;
%"TAP"
"6","(2550,3200)","2","mstr_standard","I147";
;
HDL_TAP"TRUE"
BODY_TYPE"PLUMBING"
CDS_LIB"mstr_standard";
"B \NAC \NWC"1;
"S \NAC"
BN"1"149;
%"TAP"
"6","(2550,3300)","2","mstr_standard","I148";
;
HDL_TAP"TRUE"
BODY_TYPE"PLUMBING"
CDS_LIB"mstr_standard";
"B \NAC \NWC"1;
"S \NAC"
BN"2"148;
%"TAP"
"6","(2550,3400)","2","mstr_standard","I149";
;
HDL_TAP"TRUE"
BODY_TYPE"PLUMBING"
CDS_LIB"mstr_standard";
"B \NAC \NWC"1;
"S \NAC"
BN"3"147;
%"TAP"
"6","(2550,3500)","2","mstr_standard","I150";
;
HDL_TAP"TRUE"
BODY_TYPE"PLUMBING"
CDS_LIB"mstr_standard";
"B \NAC \NWC"1;
"S \NAC"
BN"4"146;
%"TAP"
"6","(2350,3650)","2","mstr_standard","I151";
;
HDL_TAP"TRUE"
BODY_TYPE"PLUMBING"
CDS_LIB"mstr_standard";
"B \NAC \NWC"2;
"S \NAC"
BN"5"152;
%"TAP"
"6","(2350,3750)","2","mstr_standard","I152";
;
HDL_TAP"TRUE"
BODY_TYPE"PLUMBING"
CDS_LIB"mstr_standard";
"B \NAC \NWC"2;
"S \NAC"
BN"6"151;
%"TAP"
"6","(2350,3550)","2","mstr_standard","I153";
;
HDL_TAP"TRUE"
BODY_TYPE"PLUMBING"
CDS_LIB"mstr_standard";
"B \NAC \NWC"2;
"S \NAC"
BN"4"143;
%"TAP"
"6","(2350,3950)","2","mstr_standard","I154";
;
HDL_TAP"TRUE"
BODY_TYPE"PLUMBING"
CDS_LIB"mstr_standard";
"B \NAC \NWC"2;
"S \NAC"
BN"8"154;
%"TAP"
"6","(2350,3850)","2","mstr_standard","I155";
;
HDL_TAP"TRUE"
BODY_TYPE"PLUMBING"
CDS_LIB"mstr_standard";
"B \NAC \NWC"2;
"S \NAC"
BN"7"155;
%"TAP"
"6","(2550,3600)","2","mstr_standard","I156";
;
HDL_TAP"TRUE"
BODY_TYPE"PLUMBING"
CDS_LIB"mstr_standard";
"B \NAC \NWC"1;
"S \NAC"
BN"5"160;
%"TAP"
"6","(2550,3700)","2","mstr_standard","I157";
;
HDL_TAP"TRUE"
BODY_TYPE"PLUMBING"
CDS_LIB"mstr_standard";
"B \NAC \NWC"1;
"S \NAC"
BN"6"159;
%"TAP"
"6","(2550,3800)","2","mstr_standard","I158";
;
HDL_TAP"TRUE"
BODY_TYPE"PLUMBING"
CDS_LIB"mstr_standard";
"B \NAC \NWC"1;
"S \NAC"
BN"7"158;
%"TAP"
"6","(2550,3900)","2","mstr_standard","I159";
;
HDL_TAP"TRUE"
BODY_TYPE"PLUMBING"
CDS_LIB"mstr_standard";
"B \NAC \NWC"1;
"S \NAC"
BN"8"157;
%"TAP"
"6","(2550,4000)","2","mstr_standard","I160";
;
HDL_TAP"TRUE"
BODY_TYPE"PLUMBING"
CDS_LIB"mstr_standard";
"B \NAC \NWC"1;
"S \NAC"
BN"9"156;
%"GND"
"1","(4150,1100)","2","mstr_symbols","I162";
;
HDL_POWER"GND"
ROOM"DDR4_CH_A"
BODY_TYPE"PLUMBING"
CDS_LIB"mstr_symbols"
BOM_COST"MEM"
SIZE"1B"
VOLTAGE"0";
"A\NAC"17;
%"TAP"
"6","(2350,4150)","2","mstr_standard","I163";
;
HDL_TAP"TRUE"
BODY_TYPE"PLUMBING"
CDS_LIB"mstr_standard";
"B \NAC \NWC"2;
"S \NAC"
BN"10"163;
%"TAP"
"6","(2350,4250)","2","mstr_standard","I164";
;
HDL_TAP"TRUE"
BODY_TYPE"PLUMBING"
CDS_LIB"mstr_standard";
"B \NAC \NWC"2;
"S \NAC"
BN"11"162;
%"TAP"
"6","(2350,4050)","2","mstr_standard","I165";
;
HDL_TAP"TRUE"
BODY_TYPE"PLUMBING"
CDS_LIB"mstr_standard";
"B \NAC \NWC"2;
"S \NAC"
BN"9"153;
%"TAP"
"6","(2350,4350)","2","mstr_standard","I166";
;
HDL_TAP"TRUE"
BODY_TYPE"PLUMBING"
CDS_LIB"mstr_standard";
"B \NAC \NWC"2;
"S \NAC"
BN"12"161;
%"TAP"
"6","(2350,4550)","2","mstr_standard","I167";
;
HDL_TAP"TRUE"
BODY_TYPE"PLUMBING"
CDS_LIB"mstr_standard";
"B \NAC \NWC"2;
"S \NAC"
BN"14"164;
%"TAP"
"6","(2350,4450)","2","mstr_standard","I168";
;
HDL_TAP"TRUE"
BODY_TYPE"PLUMBING"
CDS_LIB"mstr_standard";
"B \NAC \NWC"2;
"S \NAC"
BN"13"165;
%"TAP"
"6","(2550,4100)","2","mstr_standard","I169";
;
HDL_TAP"TRUE"
BODY_TYPE"PLUMBING"
CDS_LIB"mstr_standard";
"B \NAC \NWC"1;
"S \NAC"
BN"10"171;
%"TAP"
"6","(2550,4300)","2","mstr_standard","I170";
;
HDL_TAP"TRUE"
BODY_TYPE"PLUMBING"
CDS_LIB"mstr_standard";
"B \NAC \NWC"1;
"S \NAC"
BN"12"169;
%"TAP"
"6","(2550,4200)","2","mstr_standard","I171";
;
HDL_TAP"TRUE"
BODY_TYPE"PLUMBING"
CDS_LIB"mstr_standard";
"B \NAC \NWC"1;
"S \NAC"
BN"11"170;
%"TAP"
"6","(2550,4400)","2","mstr_standard","I172";
;
HDL_TAP"TRUE"
BODY_TYPE"PLUMBING"
CDS_LIB"mstr_standard";
"B \NAC \NWC"1;
"S \NAC"
BN"13"168;
%"TAP"
"6","(2550,4500)","2","mstr_standard","I173";
;
HDL_TAP"TRUE"
BODY_TYPE"PLUMBING"
CDS_LIB"mstr_standard";
"B \NAC \NWC"1;
"S \NAC"
BN"14"167;
%"TAP"
"6","(2350,4650)","2","mstr_standard","I174";
;
HDL_TAP"TRUE"
BODY_TYPE"PLUMBING"
CDS_LIB"mstr_standard";
"B \NAC \NWC"2;
"S \NAC"
BN"15"174;
%"TAP"
"6","(2350,4750)","2","mstr_standard","I175";
;
HDL_TAP"TRUE"
BODY_TYPE"PLUMBING"
CDS_LIB"mstr_standard";
"B \NAC \NWC"2;
"S \NAC"
BN"16"173;
%"TAP"
"6","(2350,4850)","2","mstr_standard","I176";
;
HDL_TAP"TRUE"
BODY_TYPE"PLUMBING"
CDS_LIB"mstr_standard";
"B \NAC \NWC"2;
"S \NAC"
BN"17"172;
%"TAP"
"6","(2550,4600)","2","mstr_standard","I177";
;
HDL_TAP"TRUE"
BODY_TYPE"PLUMBING"
CDS_LIB"mstr_standard";
"B \NAC \NWC"1;
"S \NAC"
BN"15"166;
%"TAP"
"6","(2550,4800)","2","mstr_standard","I178";
;
HDL_TAP"TRUE"
BODY_TYPE"PLUMBING"
CDS_LIB"mstr_standard";
"B \NAC \NWC"1;
"S \NAC"
BN"17"175;
%"TAP"
"6","(2550,4700)","2","mstr_standard","I179";
;
HDL_TAP"TRUE"
BODY_TYPE"PLUMBING"
CDS_LIB"mstr_standard";
"B \NAC \NWC"1;
"S \NAC"
BN"16"176;
%"P12V_NVDIMM_ABC"
"1","(2300,2725)","0","mstr_symbols","I184";
;
HDL_POWER"P12V_NVDIMM_ABC"
BODY_TYPE"PLUMBING"
CDS_LIB"mstr_symbols"
VOLTAGE"12.0";
"G\NAC"18;
%"CAP_A"
"1","(-2650,1000)","2","dev_discrete","I2";
;
ROOM"DDR4_CH_A"
SEC"1"
SEC_TYPE"0402V"
CDS_SEC"1"
CDS_LIB"dev_discrete"
BOM_COST"MEM"
CDS_LOCATION"C6T1"
MATERIAL"X7R"
VOLTAGE"25V"
PACK_TYPE"0402V"
TOLERANCE"10%"
VALUE"0.01UF"
PART_NUMBER"A36096-045"
LOCATION"C6T1";
"B"
$PN"2"13;
"A"
$PN"1"22;
%"TAP"
"6","(-1450,2100)","0","mstr_standard","I21";
;
HDL_TAP"TRUE"
BODY_TYPE"PLUMBING"
CDS_LIB"mstr_standard";
"B \NAC \NWC"12;
"S \NAC"
BN"3"40;
%"TAP"
"6","(-1450,2000)","0","mstr_standard","I22";
;
HDL_TAP"TRUE"
BODY_TYPE"PLUMBING"
CDS_LIB"mstr_standard";
"B \NAC \NWC"12;
"S \NAC"
BN"1"32;
%"TAP"
"6","(-1450,2050)","0","mstr_standard","I23";
;
HDL_TAP"TRUE"
BODY_TYPE"PLUMBING"
CDS_LIB"mstr_standard";
"B \NAC \NWC"12;
"S \NAC"
BN"2"41;
%"TAP"
"6","(-1450,2150)","0","mstr_standard","I24";
;
HDL_TAP"TRUE"
BODY_TYPE"PLUMBING"
CDS_LIB"mstr_standard";
"B \NAC \NWC"12;
"S \NAC"
BN"4"39;
%"TAP"
"6","(-1450,2200)","0","mstr_standard","I25";
;
HDL_TAP"TRUE"
BODY_TYPE"PLUMBING"
CDS_LIB"mstr_standard";
"B \NAC \NWC"12;
"S \NAC"
BN"5"38;
%"TAP"
"6","(-1450,2250)","0","mstr_standard","I26";
;
HDL_TAP"TRUE"
BODY_TYPE"PLUMBING"
CDS_LIB"mstr_standard";
"B \NAC \NWC"12;
"S \NAC"
BN"6"37;
%"TAP"
"6","(-1450,2400)","0","mstr_standard","I27";
;
HDL_TAP"TRUE"
BODY_TYPE"PLUMBING"
CDS_LIB"mstr_standard";
"B \NAC \NWC"11;
"S \NAC"
BN"2"43;
%"TAP"
"6","(-1450,2450)","0","mstr_standard","I28";
;
HDL_TAP"TRUE"
BODY_TYPE"PLUMBING"
CDS_LIB"mstr_standard";
"B \NAC \NWC"11;
"S \NAC"
BN"3"44;
%"TAP"
"6","(-1450,2300)","0","mstr_standard","I29";
;
HDL_TAP"TRUE"
BODY_TYPE"PLUMBING"
CDS_LIB"mstr_standard";
"B \NAC \NWC"12;
"S \NAC"
BN"7"42;
%"GND"
"1","(-3350,1350)","2","mstr_symbols","I3";
;
HDL_POWER"GND"
ROOM"DDR4_CH_A"
BODY_TYPE"PLUMBING"
BOM_COST"MEM"
CDS_LIB"mstr_symbols"
SIZE"1B"
VOLTAGE"0";
"A\NAC"19;
%"TAP"
"6","(-1650,3000)","0","mstr_standard","I30";
;
HDL_TAP"TRUE"
BODY_TYPE"PLUMBING"
CDS_LIB"mstr_standard";
"B \NAC \NWC"8;
"S \NAC"
BN"2"36;
%"TAP"
"6","(-1450,2600)","0","mstr_standard","I31";
;
HDL_TAP"TRUE"
BODY_TYPE"PLUMBING"
CDS_LIB"mstr_standard";
"B \NAC \NWC"10;
"S \NAC"
BN"3"51;
%"TAP"
"6","(-1450,2550)","0","mstr_standard","I32";
;
HDL_TAP"TRUE"
BODY_TYPE"PLUMBING"
CDS_LIB"mstr_standard";
"B \NAC \NWC"10;
"S \NAC"
BN"2"45;
%"TAP"
"6","(-1450,2700)","0","mstr_standard","I33";
;
HDL_TAP"TRUE"
BODY_TYPE"PLUMBING"
CDS_LIB"mstr_standard";
"B \NAC \NWC"9;
"S \NAC"
BN"4"52;
%"TAP"
"6","(-1450,2750)","0","mstr_standard","I34";
;
HDL_TAP"TRUE"
BODY_TYPE"PLUMBING"
CDS_LIB"mstr_standard";
"B \NAC \NWC"9;
"S \NAC"
BN"5"50;
%"TAP"
"6","(-1450,2850)","0","mstr_standard","I35";
;
HDL_TAP"TRUE"
BODY_TYPE"PLUMBING"
CDS_LIB"mstr_standard";
"B \NAC \NWC"9;
"S \NAC"
BN"7"48;
%"TAP"
"6","(-1450,2800)","0","mstr_standard","I36";
;
HDL_TAP"TRUE"
BODY_TYPE"PLUMBING"
CDS_LIB"mstr_standard";
"B \NAC \NWC"9;
"S \NAC"
BN"6"49;
%"TAP"
"6","(-1650,3100)","0","mstr_standard","I41";
;
HDL_TAP"TRUE"
BODY_TYPE"PLUMBING"
CDS_LIB"mstr_standard";
"B \NAC \NWC"8;
"S \NAC"
BN"3"53;
%"TAP"
"6","(-1450,3150)","0","mstr_standard","I42";
;
HDL_TAP"TRUE"
BODY_TYPE"PLUMBING"
CDS_LIB"mstr_standard";
"B \NAC \NWC"7;
"S \NAC"
BN"3"57;
%"TAP"
"6","(-1450,3050)","0","mstr_standard","I43";
;
HDL_TAP"TRUE"
BODY_TYPE"PLUMBING"
CDS_LIB"mstr_standard";
"B \NAC \NWC"7;
"S \NAC"
BN"2"47;
%"TAP"
"6","(-1450,3250)","0","mstr_standard","I44";
;
HDL_TAP"TRUE"
BODY_TYPE"PLUMBING"
CDS_LIB"mstr_standard";
"B \NAC \NWC"6;
"S \NAC"
BN"0"58;
%"TAP"
"6","(-1450,3300)","0","mstr_standard","I45";
;
HDL_TAP"TRUE"
BODY_TYPE"PLUMBING"
CDS_LIB"mstr_standard";
"B \NAC \NWC"6;
"S \NAC"
BN"1"59;
%"TAP"
"6","(-1450,3400)","0","mstr_standard","I46";
;
HDL_TAP"TRUE"
BODY_TYPE"PLUMBING"
CDS_LIB"mstr_standard";
"B \NAC \NWC"5;
"S \NAC"
BN"1"54;
%"TAP"
"6","(-1450,3350)","0","mstr_standard","I47";
;
HDL_TAP"TRUE"
BODY_TYPE"PLUMBING"
CDS_LIB"mstr_standard";
"B \NAC \NWC"5;
"S \NAC"
BN"0"60;
%"TAP"
"6","(-1450,3500)","0","mstr_standard","I48";
;
HDL_TAP"TRUE"
BODY_TYPE"PLUMBING"
CDS_LIB"mstr_standard";
"B \NAC \NWC"4;
"S \NAC"
BN"0"55;
%"TAP"
"6","(-1450,3700)","0","mstr_standard","I49";
;
HDL_TAP"TRUE"
BODY_TYPE"PLUMBING"
CDS_LIB"mstr_standard";
"B \NAC \NWC"4;
"S \NAC"
BN"4"61;
%"PVPP_ABC"
"1","(-3350,1700)","0","mstr_symbols","I5";
;
HDL_POWER"PVPP_ABC"
ROOM"DDR4_CH_A"
BODY_TYPE"PLUMBING"
CDS_LIB"mstr_symbols"
BOM_COST"MEM"
VOLTAGE"2.5V";
"G\NAC"20;
%"TAP"
"6","(-1450,3600)","0","mstr_standard","I50";
;
HDL_TAP"TRUE"
BODY_TYPE"PLUMBING"
CDS_LIB"mstr_standard";
"B \NAC \NWC"4;
"S \NAC"
BN"2"70;
%"TAP"
"6","(-1450,3550)","0","mstr_standard","I51";
;
HDL_TAP"TRUE"
BODY_TYPE"PLUMBING"
CDS_LIB"mstr_standard";
"B \NAC \NWC"4;
"S \NAC"
BN"1"56;
%"TAP"
"6","(-1450,3650)","0","mstr_standard","I52";
;
HDL_TAP"TRUE"
BODY_TYPE"PLUMBING"
CDS_LIB"mstr_standard";
"B \NAC \NWC"4;
"S \NAC"
BN"3"69;
%"TAP"
"6","(-1450,3750)","0","mstr_standard","I53";
;
HDL_TAP"TRUE"
BODY_TYPE"PLUMBING"
CDS_LIB"mstr_standard";
"B \NAC \NWC"4;
"S \NAC"
BN"5"62;
%"TAP"
"6","(-1450,3900)","0","mstr_standard","I54";
;
HDL_TAP"TRUE"
BODY_TYPE"PLUMBING"
CDS_LIB"mstr_standard";
"B \NAC \NWC"4;
"S \NAC"
BN"8"65;
%"TAP"
"6","(-1450,3800)","0","mstr_standard","I55";
;
HDL_TAP"TRUE"
BODY_TYPE"PLUMBING"
CDS_LIB"mstr_standard";
"B \NAC \NWC"4;
"S \NAC"
BN"6"63;
%"TAP"
"6","(-1450,3850)","0","mstr_standard","I56";
;
HDL_TAP"TRUE"
BODY_TYPE"PLUMBING"
CDS_LIB"mstr_standard";
"B \NAC \NWC"4;
"S \NAC"
BN"7"64;
%"TAP"
"6","(-1450,3950)","0","mstr_standard","I57";
;
HDL_TAP"TRUE"
BODY_TYPE"PLUMBING"
CDS_LIB"mstr_standard";
"B \NAC \NWC"4;
"S \NAC"
BN"9"66;
%"TAP"
"6","(-1450,4000)","0","mstr_standard","I58";
;
HDL_TAP"TRUE"
BODY_TYPE"PLUMBING"
CDS_LIB"mstr_standard";
"B \NAC \NWC"4;
"S \NAC"
BN"10"67;
%"TAP"
"6","(100,1200)","2","mstr_standard","I59";
;
HDL_TAP"TRUE"
BODY_TYPE"PLUMBING"
CDS_LIB"mstr_standard";
"B \NAC \NWC"3;
"S \NAC"
BN"0"109;
%"TAP"
"6","(100,1300)","2","mstr_standard","I60";
;
HDL_TAP"TRUE"
BODY_TYPE"PLUMBING"
CDS_LIB"mstr_standard";
"B \NAC \NWC"3;
"S \NAC"
BN"2"127;
%"TAP"
"6","(100,1250)","2","mstr_standard","I61";
;
HDL_TAP"TRUE"
BODY_TYPE"PLUMBING"
CDS_LIB"mstr_standard";
"B \NAC \NWC"3;
"S \NAC"
BN"1"108;
%"TAP"
"6","(100,1350)","2","mstr_standard","I62";
;
HDL_TAP"TRUE"
BODY_TYPE"PLUMBING"
CDS_LIB"mstr_standard";
"B \NAC \NWC"3;
"S \NAC"
BN"3"128;
%"TAP"
"6","(100,1450)","2","mstr_standard","I63";
;
HDL_TAP"TRUE"
BODY_TYPE"PLUMBING"
CDS_LIB"mstr_standard";
"B \NAC \NWC"3;
"S \NAC"
BN"5"130;
%"TAP"
"6","(100,1400)","2","mstr_standard","I64";
;
HDL_TAP"TRUE"
BODY_TYPE"PLUMBING"
CDS_LIB"mstr_standard";
"B \NAC \NWC"3;
"S \NAC"
BN"4"129;
%"TAP"
"6","(100,1600)","2","mstr_standard","I65";
;
HDL_TAP"TRUE"
BODY_TYPE"PLUMBING"
CDS_LIB"mstr_standard";
"B \NAC \NWC"3;
"S \NAC"
BN"8"106;
%"TAP"
"6","(100,1550)","2","mstr_standard","I66";
;
HDL_TAP"TRUE"
BODY_TYPE"PLUMBING"
CDS_LIB"mstr_standard";
"B \NAC \NWC"3;
"S \NAC"
BN"7"107;
%"TAP"
"6","(100,1500)","2","mstr_standard","I67";
;
HDL_TAP"TRUE"
BODY_TYPE"PLUMBING"
CDS_LIB"mstr_standard";
"B \NAC \NWC"3;
"S \NAC"
BN"6"140;
%"TAP"
"6","(100,1650)","2","mstr_standard","I68";
;
HDL_TAP"TRUE"
BODY_TYPE"PLUMBING"
CDS_LIB"mstr_standard";
"B \NAC \NWC"3;
"S \NAC"
BN"9"139;
%"TAP"
"6","(100,1700)","2","mstr_standard","I69";
;
HDL_TAP"TRUE"
BODY_TYPE"PLUMBING"
CDS_LIB"mstr_standard";
"B \NAC \NWC"3;
"S \NAC"
BN"10"105;
%"TAP"
"6","(100,1800)","2","mstr_standard","I70";
;
HDL_TAP"TRUE"
BODY_TYPE"PLUMBING"
CDS_LIB"mstr_standard";
"B \NAC \NWC"3;
"S \NAC"
BN"12"104;
%"TAP"
"6","(100,1750)","2","mstr_standard","I71";
;
HDL_TAP"TRUE"
BODY_TYPE"PLUMBING"
CDS_LIB"mstr_standard";
"B \NAC \NWC"3;
"S \NAC"
BN"11"136;
%"TAP"
"6","(100,1850)","2","mstr_standard","I72";
;
HDL_TAP"TRUE"
BODY_TYPE"PLUMBING"
CDS_LIB"mstr_standard";
"B \NAC \NWC"3;
"S \NAC"
BN"13"103;
%"TAP"
"6","(100,1950)","2","mstr_standard","I73";
;
HDL_TAP"TRUE"
BODY_TYPE"PLUMBING"
CDS_LIB"mstr_standard";
"B \NAC \NWC"3;
"S \NAC"
BN"15"115;
%"TAP"
"6","(100,1900)","2","mstr_standard","I74";
;
HDL_TAP"TRUE"
BODY_TYPE"PLUMBING"
CDS_LIB"mstr_standard";
"B \NAC \NWC"3;
"S \NAC"
BN"14"134;
%"SCONN288_H44441003"
"4","(1600,1650)","0","mstr_sconn","I75";
;
CDS_SEC"4"
ROOM"DDR4_CH_A"
CDS_LOCATION"J6T1"
SEC"4"
SEC_TYPE"PIP"
CDS_LIB"mstr_sconn"
BOM_COST"MEM"
PACK_TYPE"PIP"
MATERIAL"SCONN"
PART_NUMBER"H44441-003"
LOCATION"J6T1";
"VDD<0>"
$PN"236"21;
"VDD<6>"
$PN"220"21;
"VDD<10>"
$PN"209"21;
"VDD<13>"
$PN"92"21;
"VDD<16>"
$PN"85"21;
"VDD<19>"
$PN"76"21;
"VDD<23>"
$PN"64"21;
"VDD<25>"
$PN"59"21;
"VTT<0>"
$PN"221"14;
"12V<1>"
$PN"1"18;
"12V<0>"
$PN"145"18;
"VDD<24>"
$PN"61"21;
"VDD<22>"
$PN"67"21;
"VDD<21>"
$PN"70"21;
"VDD<20>"
$PN"73"21;
"VDD<18>"
$PN"80"21;
"VDD<17>"
$PN"83"21;
"VDD<15>"
$PN"88"21;
"VDD<14>"
$PN"90"21;
"VDD<12>"
$PN"204"21;
"VDD<11>"
$PN"206"21;
"VDD<9>"
$PN"212"21;
"VDD<8>"
$PN"215"21;
"VDD<7>"
$PN"217"21;
"VDD<5>"
$PN"223"21;
"VDD<4>"
$PN"226"21;
"VDD<3>"
$PN"229"21;
"VDD<2>"
$PN"231"21;
"VDD<1>"
$PN"233"21;
"VPP<4>"
$PN"142"15;
"VPP<3>"
$PN"143"15;
"VPP<2>"
$PN"288"15;
"VPP<1>"
$PN"286"15;
"VPP<0>"
$PN"287"15;
"VTT<1>"
$PN"77"14;
%"TAP"
"6","(100,2000)","2","mstr_standard","I76";
;
HDL_TAP"TRUE"
BODY_TYPE"PLUMBING"
CDS_LIB"mstr_standard";
"B \NAC \NWC"3;
"S \NAC"
BN"16"102;
%"TAP"
"6","(100,2050)","2","mstr_standard","I77";
;
HDL_TAP"TRUE"
BODY_TYPE"PLUMBING"
CDS_LIB"mstr_standard";
"B \NAC \NWC"3;
"S \NAC"
BN"17"116;
%"TAP"
"6","(100,2100)","2","mstr_standard","I78";
;
HDL_TAP"TRUE"
BODY_TYPE"PLUMBING"
CDS_LIB"mstr_standard";
"B \NAC \NWC"3;
"S \NAC"
BN"18"135;
%"TAP"
"6","(100,2150)","2","mstr_standard","I79";
;
HDL_TAP"TRUE"
BODY_TYPE"PLUMBING"
CDS_LIB"mstr_standard";
"B \NAC \NWC"3;
"S \NAC"
BN"19"138;
%"TAP"
"6","(100,2250)","2","mstr_standard","I80";
;
HDL_TAP"TRUE"
BODY_TYPE"PLUMBING"
CDS_LIB"mstr_standard";
"B \NAC \NWC"3;
"S \NAC"
BN"21"101;
%"TAP"
"6","(100,2200)","2","mstr_standard","I81";
;
HDL_TAP"TRUE"
BODY_TYPE"PLUMBING"
CDS_LIB"mstr_standard";
"B \NAC \NWC"3;
"S \NAC"
BN"20"137;
%"TAP"
"6","(100,2300)","2","mstr_standard","I82";
;
HDL_TAP"TRUE"
BODY_TYPE"PLUMBING"
CDS_LIB"mstr_standard";
"B \NAC \NWC"3;
"S \NAC"
BN"22"100;
%"TAP"
"6","(100,2350)","2","mstr_standard","I83";
;
HDL_TAP"TRUE"
BODY_TYPE"PLUMBING"
CDS_LIB"mstr_standard";
"B \NAC \NWC"3;
"S \NAC"
BN"23"133;
%"TAP"
"6","(100,2450)","2","mstr_standard","I84";
;
HDL_TAP"TRUE"
BODY_TYPE"PLUMBING"
CDS_LIB"mstr_standard";
"B \NAC \NWC"3;
"S \NAC"
BN"25"99;
%"TAP"
"6","(100,2500)","2","mstr_standard","I85";
;
HDL_TAP"TRUE"
BODY_TYPE"PLUMBING"
CDS_LIB"mstr_standard";
"B \NAC \NWC"3;
"S \NAC"
BN"26"114;
%"TAP"
"6","(100,2400)","2","mstr_standard","I86";
;
HDL_TAP"TRUE"
BODY_TYPE"PLUMBING"
CDS_LIB"mstr_standard";
"B \NAC \NWC"3;
"S \NAC"
BN"24"132;
%"TAP"
"6","(100,2550)","2","mstr_standard","I87";
;
HDL_TAP"TRUE"
BODY_TYPE"PLUMBING"
CDS_LIB"mstr_standard";
"B \NAC \NWC"3;
"S \NAC"
BN"27"113;
%"TAP"
"6","(100,2600)","2","mstr_standard","I88";
;
HDL_TAP"TRUE"
BODY_TYPE"PLUMBING"
CDS_LIB"mstr_standard";
"B \NAC \NWC"3;
"S \NAC"
BN"28"79;
%"TAP"
"6","(100,2700)","2","mstr_standard","I89";
;
HDL_TAP"TRUE"
BODY_TYPE"PLUMBING"
CDS_LIB"mstr_standard";
"B \NAC \NWC"3;
"S \NAC"
BN"30"98;
%"TAP"
"6","(100,2650)","2","mstr_standard","I90";
;
HDL_TAP"TRUE"
BODY_TYPE"PLUMBING"
CDS_LIB"mstr_standard";
"B \NAC \NWC"3;
"S \NAC"
BN"29"78;
%"TAP"
"6","(100,2750)","2","mstr_standard","I91";
;
HDL_TAP"TRUE"
BODY_TYPE"PLUMBING"
CDS_LIB"mstr_standard";
"B \NAC \NWC"3;
"S \NAC"
BN"31"97;
%"TAP"
"6","(100,2800)","2","mstr_standard","I92";
;
HDL_TAP"TRUE"
BODY_TYPE"PLUMBING"
CDS_LIB"mstr_standard";
"B \NAC \NWC"3;
"S \NAC"
BN"32"96;
%"TAP"
"6","(100,2850)","2","mstr_standard","I93";
;
HDL_TAP"TRUE"
BODY_TYPE"PLUMBING"
CDS_LIB"mstr_standard";
"B \NAC \NWC"3;
"S \NAC"
BN"33"95;
%"TAP"
"6","(100,2900)","2","mstr_standard","I94";
;
HDL_TAP"TRUE"
BODY_TYPE"PLUMBING"
CDS_LIB"mstr_standard";
"B \NAC \NWC"3;
"S \NAC"
BN"34"94;
%"TAP"
"6","(100,2950)","2","mstr_standard","I95";
;
HDL_TAP"TRUE"
BODY_TYPE"PLUMBING"
CDS_LIB"mstr_standard";
"B \NAC \NWC"3;
"S \NAC"
BN"35"110;
%"TAP"
"6","(100,3000)","2","mstr_standard","I96";
;
HDL_TAP"TRUE"
BODY_TYPE"PLUMBING"
CDS_LIB"mstr_standard";
"B \NAC \NWC"3;
"S \NAC"
BN"36"111;
%"PVDDQ_ABC"
"1","(600,2200)","0","mstr_symbols","I97";
;
HDL_POWER"PVDDQ_ABC"
ROOM"DDR4_CH_A"
BODY_TYPE"PLUMBING"
CDS_LIB"mstr_symbols"
BOM_COST"MEM"
VOLTAGE"1.2V";
"G\NAC"21;
%"TAP"
"6","(100,3050)","2","mstr_standard","I98";
;
HDL_TAP"TRUE"
BODY_TYPE"PLUMBING"
CDS_LIB"mstr_standard";
"B \NAC \NWC"3;
"S \NAC"
BN"37"131;
%"TAP"
"6","(100,3100)","2","mstr_standard","I99";
;
HDL_TAP"TRUE"
BODY_TYPE"PLUMBING"
CDS_LIB"mstr_standard";
"B \NAC \NWC"3;
"S \NAC"
BN"38"112;
END.
